(kicad_pcb
	(version 20241229)
	(generator "pcbnew")
	(generator_version "9.0")
	(general
		(thickness 1.599998)
		(legacy_teardrops no)
	)
	(paper "A4")
	(title_block
		(date "2023-02-12")
		(rev "1.1.5")
		(comment 9 "footprints 385-391 of 473")
	)
	(layers
		(0 "F.Cu" signal)
		(4 "In1.Cu" power "In1.GND")
		(6 "In2.Cu" signal)
		(8 "In3.Cu" power "In3.GND")
		(10 "In4.Cu" power "In4.VCC")
		(12 "In5.Cu" signal)
		(14 "In6.Cu" power "In6.VCC")
		(2 "B.Cu" signal)
		(9 "F.Adhes" user "F.Adhesive")
		(11 "B.Adhes" user "B.Adhesive")
		(13 "F.Paste" user)
		(15 "B.Paste" user)
		(5 "F.SilkS" user "F.Silkscreen")
		(7 "B.SilkS" user "B.Silkscreen")
		(1 "F.Mask" user)
		(3 "B.Mask" user)
		(17 "Dwgs.User" user "User.Drawings")
		(19 "Cmts.User" user "User.Comments")
		(21 "Eco1.User" user "User.Eco1")
		(23 "Eco2.User" user "User.Eco2")
		(25 "Edge.Cuts" user)
		(27 "Margin" user)
		(31 "F.CrtYd" user "F.Courtyard")
		(29 "B.CrtYd" user "B.Courtyard")
		(35 "F.Fab" user)
		(33 "B.Fab" user)
	)
	(footprint "antmicro-footprints:C_0402_1005Metric"
		(layer "B.Cu")
		(at 160.5 101.125)
		(descr "Capacitor SMD 0402")
		(tags "capacitor SMD 0402")
		(property "Reference" "C79"
			(at -0.8 0.375 180)
			(layer "B.SilkS")
			(effects
				(font
					(size 0.7 0.7)
					(thickness 0.15)
				)
				(justify left bottom mirror)
			)
		)
		(property "Value" "C_4u7_0402"
			(at 0 -1.4 180)
			(layer "B.Fab")
			(effects
				(font
					(size 0.7 0.7)
					(thickness 0.15)
				)
				(justify left bottom mirror)
			)
		)
		(property "Description" " "
			(at 0 0 0)
			(layer "F.Fab")
			(hide yes)
			(effects
				(font
					(size 1.27 1.27)
					(thickness 0.15)
				)
			)
		)
		(property "Author" "Antmicro"
			(at 0 0 0)
			(layer "B.Fab")
			(hide yes)
			(effects
				(font
					(size 1 1)
					(thickness 0.15)
				)
				(justify mirror)
			)
		)
		(property "Dielectric" ""
			(at 0 0 0)
			(layer "B.Fab")
			(hide yes)
			(effects
				(font
					(size 1 1)
					(thickness 0.15)
				)
				(justify mirror)
			)
		)
		(property "License" "Apache-2.0"
			(at 0 0 0)
			(layer "B.Fab")
			(hide yes)
			(effects
				(font
					(size 1 1)
					(thickness 0.15)
				)
				(justify mirror)
			)
		)
		(property "MPN" "GRM155R61A475MEAAD"
			(at 0 0 0)
			(layer "B.Fab")
			(hide yes)
			(effects
				(font
					(size 1 1)
					(thickness 0.15)
				)
				(justify mirror)
			)
		)
		(property "Manufacturer" "Murata"
			(at 0 0 0)
			(layer "B.Fab")
			(hide yes)
			(effects
				(font
					(size 1 1)
					(thickness 0.15)
				)
				(justify mirror)
			)
		)
		(property "Val" "4u7"
			(at 0 0 0)
			(layer "B.Fab")
			(hide yes)
			(effects
				(font
					(size 1 1)
					(thickness 0.15)
				)
				(justify mirror)
			)
		)
		(property "Voltage" ""
			(at 0 0 0)
			(layer "B.Fab")
			(hide yes)
			(effects
				(font
					(size 1 1)
					(thickness 0.15)
				)
				(justify mirror)
			)
		)
		(sheetname "FPGA power")
		(sheetfile "fpga-power.kicad_sch")
		(attr smd)
		(fp_rect
			(start -0.94 0.47)
			(end 0.94 -0.47)
			(stroke
				(width 0.05)
				(type solid)
			)
			(fill no)
			(layer "B.CrtYd")
		)
		(fp_rect
			(start -0.499 0.249)
			(end 0.499 -0.249)
			(stroke
				(width 0.15)
				(type solid)
			)
			(fill no)
			(layer "B.Fab")
		)
		(pad "1" smd roundrect
			(at -0.484 0)
			(size 0.59 0.64)
			(layers "B.Cu" "B.Mask" "B.Paste")
			(roundrect_rratio 0.25)
			(net 459 "3V3_SYS")
			(pintype "passive")
		)
		(pad "2" smd roundrect
			(at 0.484 0)
			(size 0.59 0.64)
			(layers "B.Cu" "B.Mask" "B.Paste")
			(roundrect_rratio 0.25)
			(net 5 "GND")
			(pintype "passive")
		)
	)
	(footprint "antmicro-footprints:C_0402_1005Metric"
		(layer "B.Cu")
		(at 159.1564 99.1362)
		(descr "Capacitor SMD 0402")
		(tags "capacitor SMD 0402")
		(property "Reference" "C82"
			(at -0.7564 0.3638 180)
			(layer "B.SilkS")
			(effects
				(font
					(size 0.7 0.7)
					(thickness 0.15)
				)
				(justify left bottom mirror)
			)
		)
		(property "Value" "C_4u7_0402"
			(at 0 -1.4 180)
			(layer "B.Fab")
			(effects
				(font
					(size 0.7 0.7)
					(thickness 0.15)
				)
				(justify left bottom mirror)
			)
		)
		(property "Description" " "
			(at 0 0 0)
			(layer "F.Fab")
			(hide yes)
			(effects
				(font
					(size 1.27 1.27)
					(thickness 0.15)
				)
			)
		)
		(property "Author" "Antmicro"
			(at 0 0 0)
			(layer "B.Fab")
			(hide yes)
			(effects
				(font
					(size 1 1)
					(thickness 0.15)
				)
				(justify mirror)
			)
		)
		(property "Dielectric" ""
			(at 0 0 0)
			(layer "B.Fab")
			(hide yes)
			(effects
				(font
					(size 1 1)
					(thickness 0.15)
				)
				(justify mirror)
			)
		)
		(property "License" "Apache-2.0"
			(at 0 0 0)
			(layer "B.Fab")
			(hide yes)
			(effects
				(font
					(size 1 1)
					(thickness 0.15)
				)
				(justify mirror)
			)
		)
		(property "MPN" "GRM155R61A475MEAAD"
			(at 0 0 0)
			(layer "B.Fab")
			(hide yes)
			(effects
				(font
					(size 1 1)
					(thickness 0.15)
				)
				(justify mirror)
			)
		)
		(property "Manufacturer" "Murata"
			(at 0 0 0)
			(layer "B.Fab")
			(hide yes)
			(effects
				(font
					(size 1 1)
					(thickness 0.15)
				)
				(justify mirror)
			)
		)
		(property "Val" "4u7"
			(at 0 0 0)
			(layer "B.Fab")
			(hide yes)
			(effects
				(font
					(size 1 1)
					(thickness 0.15)
				)
				(justify mirror)
			)
		)
		(property "Voltage" ""
			(at 0 0 0)
			(layer "B.Fab")
			(hide yes)
			(effects
				(font
					(size 1 1)
					(thickness 0.15)
				)
				(justify mirror)
			)
		)
		(sheetname "FPGA power")
		(sheetfile "fpga-power.kicad_sch")
		(attr smd)
		(fp_rect
			(start -0.94 0.47)
			(end 0.94 -0.47)
			(stroke
				(width 0.05)
				(type solid)
			)
			(fill no)
			(layer "B.CrtYd")
		)
		(fp_rect
			(start -0.499 0.249)
			(end 0.499 -0.249)
			(stroke
				(width 0.15)
				(type solid)
			)
			(fill no)
			(layer "B.Fab")
		)
		(pad "1" smd roundrect
			(at -0.484 0)
			(size 0.59 0.64)
			(layers "B.Cu" "B.Mask" "B.Paste")
			(roundrect_rratio 0.25)
			(net 459 "3V3_SYS")
			(pintype "passive")
		)
		(pad "2" smd roundrect
			(at 0.484 0)
			(size 0.59 0.64)
			(layers "B.Cu" "B.Mask" "B.Paste")
			(roundrect_rratio 0.25)
			(net 5 "GND")
			(pintype "passive")
		)
	)
	(footprint "antmicro-footprints:C_0402_1005Metric"
		(layer "B.Cu")
		(at 159.5 103.125 180)
		(descr "Capacitor SMD 0402")
		(tags "capacitor SMD 0402")
		(property "Reference" "C85"
			(at 0.8 -0.375 0)
			(layer "B.SilkS")
			(effects
				(font
					(size 0.7 0.7)
					(thickness 0.15)
				)
				(justify left bottom mirror)
			)
		)
		(property "Value" "C_4u7_0402"
			(at 0 -1.4 0)
			(layer "B.Fab")
			(effects
				(font
					(size 0.7 0.7)
					(thickness 0.15)
				)
				(justify left bottom mirror)
			)
		)
		(property "Description" " "
			(at 0 0 180)
			(layer "F.Fab")
			(hide yes)
			(effects
				(font
					(size 1.27 1.27)
					(thickness 0.15)
				)
			)
		)
		(property "Author" "Antmicro"
			(at 319 206.25 0)
			(layer "B.Fab")
			(hide yes)
			(effects
				(font
					(size 1 1)
					(thickness 0.15)
				)
				(justify mirror)
			)
		)
		(property "Dielectric" ""
			(at 319 206.25 0)
			(layer "B.Fab")
			(hide yes)
			(effects
				(font
					(size 1 1)
					(thickness 0.15)
				)
				(justify mirror)
			)
		)
		(property "License" "Apache-2.0"
			(at 319 206.25 0)
			(layer "B.Fab")
			(hide yes)
			(effects
				(font
					(size 1 1)
					(thickness 0.15)
				)
				(justify mirror)
			)
		)
		(property "MPN" "GRM155R61A475MEAAD"
			(at 319 206.25 0)
			(layer "B.Fab")
			(hide yes)
			(effects
				(font
					(size 1 1)
					(thickness 0.15)
				)
				(justify mirror)
			)
		)
		(property "Manufacturer" "Murata"
			(at 319 206.25 0)
			(layer "B.Fab")
			(hide yes)
			(effects
				(font
					(size 1 1)
					(thickness 0.15)
				)
				(justify mirror)
			)
		)
		(property "Val" "4u7"
			(at 319 206.25 0)
			(layer "B.Fab")
			(hide yes)
			(effects
				(font
					(size 1 1)
					(thickness 0.15)
				)
				(justify mirror)
			)
		)
		(property "Voltage" ""
			(at 319 206.25 0)
			(layer "B.Fab")
			(hide yes)
			(effects
				(font
					(size 1 1)
					(thickness 0.15)
				)
				(justify mirror)
			)
		)
		(sheetname "FPGA power")
		(sheetfile "fpga-power.kicad_sch")
		(attr smd)
		(fp_rect
			(start -0.94 0.47)
			(end 0.94 -0.47)
			(stroke
				(width 0.05)
				(type solid)
			)
			(fill no)
			(layer "B.CrtYd")
		)
		(fp_rect
			(start -0.499 0.249)
			(end 0.499 -0.249)
			(stroke
				(width 0.15)
				(type solid)
			)
			(fill no)
			(layer "B.Fab")
		)
		(pad "1" smd roundrect
			(at -0.484 0 180)
			(size 0.59 0.64)
			(layers "B.Cu" "B.Mask" "B.Paste")
			(roundrect_rratio 0.25)
			(net 459 "3V3_SYS")
			(pintype "passive")
		)
		(pad "2" smd roundrect
			(at 0.484 0 180)
			(size 0.59 0.64)
			(layers "B.Cu" "B.Mask" "B.Paste")
			(roundrect_rratio 0.25)
			(net 5 "GND")
			(pintype "passive")
		)
	)
	(footprint "antmicro-footprints:C_0402_1005Metric"
		(layer "B.Cu")
		(at 163.5 105.125 180)
		(descr "Capacitor SMD 0402")
		(tags "capacitor SMD 0402")
		(property "Reference" "C87"
			(at -1.2 -1.275 0)
			(layer "B.SilkS")
			(effects
				(font
					(size 0.7 0.7)
					(thickness 0.15)
				)
				(justify left bottom mirror)
			)
		)
		(property "Value" "C_4u7_0402"
			(at 0 -1.4 0)
			(layer "B.Fab")
			(effects
				(font
					(size 0.7 0.7)
					(thickness 0.15)
				)
				(justify left bottom mirror)
			)
		)
		(property "Description" " "
			(at 0 0 180)
			(layer "F.Fab")
			(hide yes)
			(effects
				(font
					(size 1.27 1.27)
					(thickness 0.15)
				)
			)
		)
		(property "Author" "Antmicro"
			(at 327 210.25 0)
			(layer "B.Fab")
			(hide yes)
			(effects
				(font
					(size 1 1)
					(thickness 0.15)
				)
				(justify mirror)
			)
		)
		(property "Dielectric" ""
			(at 327 210.25 0)
			(layer "B.Fab")
			(hide yes)
			(effects
				(font
					(size 1 1)
					(thickness 0.15)
				)
				(justify mirror)
			)
		)
		(property "License" "Apache-2.0"
			(at 327 210.25 0)
			(layer "B.Fab")
			(hide yes)
			(effects
				(font
					(size 1 1)
					(thickness 0.15)
				)
				(justify mirror)
			)
		)
		(property "MPN" "GRM155R61A475MEAAD"
			(at 327 210.25 0)
			(layer "B.Fab")
			(hide yes)
			(effects
				(font
					(size 1 1)
					(thickness 0.15)
				)
				(justify mirror)
			)
		)
		(property "Manufacturer" "Murata"
			(at 327 210.25 0)
			(layer "B.Fab")
			(hide yes)
			(effects
				(font
					(size 1 1)
					(thickness 0.15)
				)
				(justify mirror)
			)
		)
		(property "Val" "4u7"
			(at 327 210.25 0)
			(layer "B.Fab")
			(hide yes)
			(effects
				(font
					(size 1 1)
					(thickness 0.15)
				)
				(justify mirror)
			)
		)
		(property "Voltage" ""
			(at 327 210.25 0)
			(layer "B.Fab")
			(hide yes)
			(effects
				(font
					(size 1 1)
					(thickness 0.15)
				)
				(justify mirror)
			)
		)
		(sheetname "FPGA power")
		(sheetfile "fpga-power.kicad_sch")
		(attr smd)
		(fp_rect
			(start -0.94 0.47)
			(end 0.94 -0.47)
			(stroke
				(width 0.05)
				(type solid)
			)
			(fill no)
			(layer "B.CrtYd")
		)
		(fp_rect
			(start -0.499 0.249)
			(end 0.499 -0.249)
			(stroke
				(width 0.15)
				(type solid)
			)
			(fill no)
			(layer "B.Fab")
		)
		(pad "1" smd roundrect
			(at -0.484 0 180)
			(size 0.59 0.64)
			(layers "B.Cu" "B.Mask" "B.Paste")
			(roundrect_rratio 0.25)
			(net 459 "3V3_SYS")
			(pintype "passive")
		)
		(pad "2" smd roundrect
			(at 0.484 0 180)
			(size 0.59 0.64)
			(layers "B.Cu" "B.Mask" "B.Paste")
			(roundrect_rratio 0.25)
			(net 5 "GND")
			(pintype "passive")
		)
	)
	(footprint "antmicro-footprints:C_0402_1005Metric"
		(layer "B.Cu")
		(at 178.586328 106.974306)
		(descr "Capacitor SMD 0402")
		(tags "capacitor SMD 0402")
		(property "Reference" "C91"
			(at 1.113672 1.225694 180)
			(layer "B.SilkS")
			(effects
				(font
					(size 0.7 0.7)
					(thickness 0.15)
				)
				(justify left bottom mirror)
			)
		)
		(property "Value" "C_4u7_0402"
			(at 0 -1.4 180)
			(layer "B.Fab")
			(effects
				(font
					(size 0.7 0.7)
					(thickness 0.15)
				)
				(justify left bottom mirror)
			)
		)
		(property "Description" " "
			(at 0 0 0)
			(layer "F.Fab")
			(hide yes)
			(effects
				(font
					(size 1.27 1.27)
					(thickness 0.15)
				)
			)
		)
		(property "Author" "Antmicro"
			(at 0 0 0)
			(layer "B.Fab")
			(hide yes)
			(effects
				(font
					(size 1 1)
					(thickness 0.15)
				)
				(justify mirror)
			)
		)
		(property "Dielectric" ""
			(at 0 0 0)
			(layer "B.Fab")
			(hide yes)
			(effects
				(font
					(size 1 1)
					(thickness 0.15)
				)
				(justify mirror)
			)
		)
		(property "License" "Apache-2.0"
			(at 0 0 0)
			(layer "B.Fab")
			(hide yes)
			(effects
				(font
					(size 1 1)
					(thickness 0.15)
				)
				(justify mirror)
			)
		)
		(property "MPN" "GRM155R61A475MEAAD"
			(at 0 0 0)
			(layer "B.Fab")
			(hide yes)
			(effects
				(font
					(size 1 1)
					(thickness 0.15)
				)
				(justify mirror)
			)
		)
		(property "Manufacturer" "Murata"
			(at 0 0 0)
			(layer "B.Fab")
			(hide yes)
			(effects
				(font
					(size 1 1)
					(thickness 0.15)
				)
				(justify mirror)
			)
		)
		(property "Val" "4u7"
			(at 0 0 0)
			(layer "B.Fab")
			(hide yes)
			(effects
				(font
					(size 1 1)
					(thickness 0.15)
				)
				(justify mirror)
			)
		)
		(property "Voltage" ""
			(at 0 0 0)
			(layer "B.Fab")
			(hide yes)
			(effects
				(font
					(size 1 1)
					(thickness 0.15)
				)
				(justify mirror)
			)
		)
		(sheetname "FPGA power")
		(sheetfile "fpga-power.kicad_sch")
		(attr smd)
		(fp_rect
			(start -0.94 0.47)
			(end 0.94 -0.47)
			(stroke
				(width 0.05)
				(type solid)
			)
			(fill no)
			(layer "B.CrtYd")
		)
		(fp_rect
			(start -0.499 0.249)
			(end 0.499 -0.249)
			(stroke
				(width 0.15)
				(type solid)
			)
			(fill no)
			(layer "B.Fab")
		)
		(pad "1" smd roundrect
			(at -0.484 0)
			(size 0.59 0.64)
			(layers "B.Cu" "B.Mask" "B.Paste")
			(roundrect_rratio 0.25)
			(net 459 "3V3_SYS")
			(pintype "passive")
		)
		(pad "2" smd roundrect
			(at 0.484 0)
			(size 0.59 0.64)
			(layers "B.Cu" "B.Mask" "B.Paste")
			(roundrect_rratio 0.25)
			(net 5 "GND")
			(pintype "passive")
		)
	)
	(footprint "antmicro-footprints:C_0402_1005Metric"
		(layer "B.Cu")
		(at 170.75 93 180)
		(descr "Capacitor SMD 0402")
		(tags "capacitor SMD 0402")
		(property "Reference" "C84"
			(at -1.15 0.4 0)
			(layer "B.SilkS")
			(effects
				(font
					(size 0.7 0.7)
					(thickness 0.15)
				)
				(justify left bottom mirror)
			)
		)
		(property "Value" "C_4u7_0402"
			(at 0 -1.4 0)
			(layer "B.Fab")
			(effects
				(font
					(size 0.7 0.7)
					(thickness 0.15)
				)
				(justify left bottom mirror)
			)
		)
		(property "Description" " "
			(at 0 0 180)
			(layer "F.Fab")
			(hide yes)
			(effects
				(font
					(size 1.27 1.27)
					(thickness 0.15)
				)
			)
		)
		(property "Author" "Antmicro"
			(at 341.5 186 0)
			(layer "B.Fab")
			(hide yes)
			(effects
				(font
					(size 1 1)
					(thickness 0.15)
				)
				(justify mirror)
			)
		)
		(property "Dielectric" ""
			(at 341.5 186 0)
			(layer "B.Fab")
			(hide yes)
			(effects
				(font
					(size 1 1)
					(thickness 0.15)
				)
				(justify mirror)
			)
		)
		(property "License" "Apache-2.0"
			(at 341.5 186 0)
			(layer "B.Fab")
			(hide yes)
			(effects
				(font
					(size 1 1)
					(thickness 0.15)
				)
				(justify mirror)
			)
		)
		(property "MPN" "GRM155R61A475MEAAD"
			(at 341.5 186 0)
			(layer "B.Fab")
			(hide yes)
			(effects
				(font
					(size 1 1)
					(thickness 0.15)
				)
				(justify mirror)
			)
		)
		(property "Manufacturer" "Murata"
			(at 341.5 186 0)
			(layer "B.Fab")
			(hide yes)
			(effects
				(font
					(size 1 1)
					(thickness 0.15)
				)
				(justify mirror)
			)
		)
		(property "Val" "4u7"
			(at 341.5 186 0)
			(layer "B.Fab")
			(hide yes)
			(effects
				(font
					(size 1 1)
					(thickness 0.15)
				)
				(justify mirror)
			)
		)
		(property "Voltage" ""
			(at 341.5 186 0)
			(layer "B.Fab")
			(hide yes)
			(effects
				(font
					(size 1 1)
					(thickness 0.15)
				)
				(justify mirror)
			)
		)
		(sheetname "FPGA power")
		(sheetfile "fpga-power.kicad_sch")
		(attr smd)
		(fp_rect
			(start -0.94 0.47)
			(end 0.94 -0.47)
			(stroke
				(width 0.05)
				(type solid)
			)
			(fill no)
			(layer "B.CrtYd")
		)
		(fp_rect
			(start -0.499 0.249)
			(end 0.499 -0.249)
			(stroke
				(width 0.15)
				(type solid)
			)
			(fill no)
			(layer "B.Fab")
		)
		(pad "1" smd roundrect
			(at -0.484 0 180)
			(size 0.59 0.64)
			(layers "B.Cu" "B.Mask" "B.Paste")
			(roundrect_rratio 0.25)
			(net 465 "1V0_SYS")
			(pintype "passive")
		)
		(pad "2" smd roundrect
			(at 0.484 0 180)
			(size 0.59 0.64)
			(layers "B.Cu" "B.Mask" "B.Paste")
			(roundrect_rratio 0.25)
			(net 5 "GND")
			(pintype "passive")
		)
	)
	(footprint "antmicro-footprints:C_0201"
		(layer "B.Cu")
		(at 169.036328 92.367157 180)
		(descr "Capacitor SMD 0201")
		(tags "capacitor SMD 0201")
		(property "Reference" "C56"
			(at -2.463672 1.767157 0)
			(layer "B.SilkS")
			(effects
				(font
					(size 0.7 0.7)
					(thickness 0.15)
				)
				(justify left bottom mirror)
			)
		)
		(property "Value" "C_100n_0201"
			(at 0 -1.4 0)
			(layer "B.Fab")
			(effects
				(font
					(size 0.7 0.7)
					(thickness 0.15)
				)
				(justify left bottom mirror)
			)
		)
		(property "Description" " "
			(at 0 0 180)
			(layer "F.Fab")
			(hide yes)
			(effects
				(font
					(size 1.27 1.27)
					(thickness 0.15)
				)
			)
		)
		(property "Author" "Antmicro"
			(at 338.072656 184.734314 0)
			(layer "B.Fab")
			(hide yes)
			(effects
				(font
					(size 1 1)
					(thickness 0.15)
				)
				(justify mirror)
			)
		)
		(property "Dielectric" ""
			(at 338.072656 184.734314 0)
			(layer "B.Fab")
			(hide yes)
			(effects
				(font
					(size 1 1)
					(thickness 0.15)
				)
				(justify mirror)
			)
		)
		(property "License" "Apache-2.0"
			(at 338.072656 184.734314 0)
			(layer "B.Fab")
			(hide yes)
			(effects
				(font
					(size 1 1)
					(thickness 0.15)
				)
				(justify mirror)
			)
		)
		(property "MPN" "CC0201KRX6S5BB104"
			(at 338.072656 184.734314 0)
			(layer "B.Fab")
			(hide yes)
			(effects
				(font
					(size 1 1)
					(thickness 0.15)
				)
				(justify mirror)
			)
		)
		(property "Manufacturer" "Yaego"
			(at 338.072656 184.734314 0)
			(layer "B.Fab")
			(hide yes)
			(effects
				(font
					(size 1 1)
					(thickness 0.15)
				)
				(justify mirror)
			)
		)
		(property "Val" "100n"
			(at 338.072656 184.734314 0)
			(layer "B.Fab")
			(hide yes)
			(effects
				(font
					(size 1 1)
					(thickness 0.15)
				)
				(justify mirror)
			)
		)
		(property "Voltage" ""
			(at 338.072656 184.734314 0)
			(layer "B.Fab")
			(hide yes)
			(effects
				(font
					(size 1 1)
					(thickness 0.15)
				)
				(justify mirror)
			)
		)
		(sheetname "FPGA power")
		(sheetfile "fpga-power.kicad_sch")
		(attr smd)
		(fp_rect
			(start -0.72 0.38)
			(end 0.72 -0.38)
			(stroke
				(width 0.05)
				(type solid)
			)
			(fill no)
			(layer "B.CrtYd")
		)
		(fp_rect
			(start 0.3 -0.15)
			(end -0.301 0.149)
			(stroke
				(width 0.15)
				(type solid)
			)
			(fill no)
			(layer "B.Fab")
		)
		(pad "" smd roundrect
			(at -0.349 0.002 180)
			(size 0.318 0.36)
			(layers "B.Paste")
			(roundrect_rratio 0.25)
		)
		(pad "" smd roundrect
			(at 0.341 0.002 180)
			(size 0.318 0.36)
			(layers "B.Paste")
			(roundrect_rratio 0.25)
		)
		(pad "1" smd roundrect
			(at -0.321 0.002 180)
			(size 0.46 0.4)
			(layers "B.Cu" "B.Mask")
			(roundrect_rratio 0.25)
			(net 465 "1V0_SYS")
			(pintype "passive")
		)
		(pad "2" smd roundrect
			(at 0.32 0.002 180)
			(size 0.46 0.4)
			(layers "B.Cu" "B.Mask")
			(roundrect_rratio 0.25)
			(net 5 "GND")
			(pintype "passive")
		)
	)
)
